# S9S_MB_2U (Grand Teton) — schematic netlist excerpt (pin names and nets, part order shuffled) for the footprints in the layout excerpt that follows; sources: Cadence DE-HDL packaged netlist, KiCad conversion of 03242023_DA0F0TMBIJ0_F0T_Motherboard_J_brd_V01_OCP.brd

J4  SCONN288_ADR50017P087CC  SCONN288_ADR50017-P087CC IO  pkg DDR288S_1-1VXB  page 85
  VIN_BULK0  = P12V_S3_AUX_CPU0_NVDIMM
  RFU0  = TP_CHB_CPU0_DIMM2_FRU_0
  VIN_MGMT  = P3V3_AUX
  HSCL  = I3C_SPD_DDRABCD_CPU0_LVC1_SCL_3
  HSDA  = I3C_SPD_DDRABCD_CPU0_LVC1_SDA
  VSS0  = GND
  DQ0_A  = M_B_CPU0_SA_DQ<0>
  VSS1  = GND
  DQ1_A  = M_B_CPU0_SA_DQ<1>
  VSS2  = GND
  DQS0_A_T  = M_B_CPU0_SA_DQS_DP<0>
  DQS0_A_C  = M_B_CPU0_SA_DQS_DN<0>
  VSS3  = GND
  DQ4_A  = M_B_CPU0_SA_DQ<4>
  VSS4  = GND
  DQ5_A  = M_B_CPU0_SA_DQ<5>
  VSS5  = GND
  DQ8_A  = M_B_CPU0_SA_DQ<8>
  VSS6  = GND
  DQ9_A  = M_B_CPU0_SA_DQ<9>
  VSS7  = GND
  DQS1_A_T  = M_B_CPU0_SA_DQS_DP<1>
  DQS1_A_C  = M_B_CPU0_SA_DQS_DN<1>
  VSS8  = GND
  DQ12_A  = M_B_CPU0_SA_DQ<12>
  VSS9  = GND
  DQ13_A  = M_B_CPU0_SA_DQ<13>
  VSS10  = GND
  DQ16_A  = M_B_CPU0_SA_DQ<16>
  VSS11  = GND
  DQ17_A  = M_B_CPU0_SA_DQ<17>
  VSS12  = GND
  DQS2_A_T  = M_B_CPU0_SA_DQS_DP<2>
  DQS2_A_C  = M_B_CPU0_SA_DQS_DN<2>
  VSS13  = GND
  DQ20_A  = M_B_CPU0_SA_DQ<20>
  VSS14  = GND
  DQ21_A  = M_B_CPU0_SA_DQ<21>
  VSS15  = GND
  DQ24_A  = M_B_CPU0_SA_DQ<24>
  VSS16  = GND
  DQ25_A  = M_B_CPU0_SA_DQ<25>
  VSS17  = GND
  DQS3_A_T  = M_B_CPU0_SA_DQS_DP<3>
  DQS3_A_C  = M_B_CPU0_SA_DQS_DN<3>
  VSS18  = GND
  DQ28_A  = M_B_CPU0_SA_DQ<28>
  VSS19  = GND
  DQ29_A  = M_B_CPU0_SA_DQ<29>
  VSS20  = GND
  CB0_A  = M_B_CPU0_SA_CB<0>
  VSS21  = GND
  CB1_A  = M_B_CPU0_SA_CB<1>
  VSS22  = GND
  DQS4_A_T  = M_B_CPU0_SA_DQS_DP<4>
  DQS4_A_C  = M_B_CPU0_SA_DQS_DN<4>
  VSS23  = GND
  CB4_A  = M_B_CPU0_SA_CB<4>
  VSS24  = GND
  CB5_A  = M_B_CPU0_SA_CB<5>
  VSS25  = GND
  ALERT_N  = M_B_CPU0_ALERT_N
  VSS26  = GND
  CS0_A_N  = M_B_CPU0_SA_CS_N<2>
  VSS27  = GND
  CA0_A  = M_B_CPU0_SA_CA<0>
  VSS28  = GND
  CA2_A  = M_B_CPU0_SA_CA<2>
  VSS29  = GND
  CA4_A  = M_B_CPU0_SA_CA<4>
  VSS30  = GND
  CA6_A  = M_B_CPU0_SA_CA<6>
  VSS31  = GND
  PAR_A  = M_B_CPU0_SA_PAR
  VSS32  = GND
  CA0_B  = M_B_CPU0_SB_CA<0>
  VSS33  = GND
  CA2_B  = M_B_CPU0_SB_CA<2>
  VSS34  = GND
  CA4_B  = M_B_CPU0_SB_CA<4>
  VSS35  = GND
  CA6_B  = M_B_CPU0_SB_CA<6>
  VSS36  = GND
  CS0_B_N  = M_B_CPU0_SB_CS_N<2>
  VSS37  = GND
  \lbd||rsp_a_n\  = M_B_CPU0_SA_RSP<1>
  \lbs||rsp_b_n\  = M_B_CPU0_SB_RSP<1>
  VSS38  = GND
  CB4_B  = M_B_CPU0_SB_CB<4>
  VSS39  = GND
  CB5_B  = M_B_CPU0_SB_CB<5>
  VSS40  = GND
  \dqs9_b_t||tdqs9_b_t||dbi4_b_n\  = M_B_CPU0_SB_DQS_DP<9>
  \dqs9_b_c||tdqs9_b_c\  = M_B_CPU0_SB_DQS_DN<9>
  VSS41  = GND
  CB0_B  = M_B_CPU0_SB_CB<0>
  VSS42  = GND
  CB1_B  = M_B_CPU0_SB_CB<1>
  VSS43  = GND
  DQ0_B  = M_B_CPU0_SB_DQ<0>
  VSS44  = GND
  DQ1_B  = M_B_CPU0_SB_DQ<1>
  VSS45  = GND
  DQS0_B_T  = M_B_CPU0_SB_DQS_DP<0>
  DQS0_B_C  = M_B_CPU0_SB_DQS_DN<0>
  VSS46  = GND
  DQ4_B  = M_B_CPU0_SB_DQ<4>
  VSS47  = GND
  DQ5_B  = M_B_CPU0_SB_DQ<5>
  VSS48  = GND
  DQ8_B  = M_B_CPU0_SB_DQ<8>
  VSS49  = GND
  DQ9_B  = M_B_CPU0_SB_DQ<9>
  VSS50  = GND
  DQS1_B_T  = M_B_CPU0_SB_DQS_DP<1>
  DQS1_B_C  = M_B_CPU0_SB_DQS_DN<1>
  VSS51  = GND
  DQ12_B  = M_B_CPU0_SB_DQ<12>
  VSS52  = GND
  DQ13_B  = M_B_CPU0_SB_DQ<13>
  VSS53  = GND
  DQ16_B  = M_B_CPU0_SB_DQ<16>
  VSS54  = GND
  DQ17_B  = M_B_CPU0_SB_DQ<17>
  VSS55  = GND
  DQS2_B_T  = M_B_CPU0_SB_DQS_DP<2>
  DQS2_B_C  = M_B_CPU0_SB_DQS_DN<2>
  VSS56  = GND
  DQ20_B  = M_B_CPU0_SB_DQ<20>
  VSS57  = GND
  DQ21_B  = M_B_CPU0_SB_DQ<21>
  VSS58  = GND
  DQ24_B  = M_B_CPU0_SB_DQ<24>
  VSS59  = GND
  DQ25_B  = M_B_CPU0_SB_DQ<25>
  VSS60  = GND
  DQS3_B_T  = M_B_CPU0_SB_DQS_DP<3>
  DQS3_B_C  = M_B_CPU0_SB_DQS_DN<3>
  VSS61  = GND
  DQ28_B  = M_B_CPU0_SB_DQ<28>
  VSS62  = GND
  DQ29_B  = M_B_CPU0_SB_DQ<29>
  VSS63  = GND
  RFU1  = TP_CHB_CPU0_DIMM2_FRU_1
  VIN_BULK1  = P12V_S3_AUX_CPU0_NVDIMM
  VIN_BULK2  = P12V_S3_AUX_CPU0_NVDIMM
  \pwr_good||fail_n\  = PWRGD_CHB_CPU0_DIMM2
  HSA  = PD_CHB_CPU0_DIMM2_SAA
  RFU2  = TP_CHB_CPU0_DIMM2_FRU_2
  RFU3  = TP_CHB_CPU0_DIMM2_FRU_3
  VSS64  = GND
  DQ2_A  = M_B_CPU0_SA_DQ<2>
  VSS65  = GND
  DQ3_A  = M_B_CPU0_SA_DQ<3>
  VSS66  = GND
  \dqs5_a_c||tdqs5_a_c||dqs5_a_t||tdqs5_a_t\  = M_B_CPU0_SA_DQS_DN<5>
  \dqs5_a_t||tdqs5_a_t\  = M_B_CPU0_SA_DQS_DP<5>
  VSS67  = GND
  DQ6_A  = M_B_CPU0_SA_DQ<6>
  VSS68  = GND
  DQ7_A  = M_B_CPU0_SA_DQ<7>
  VSS69  = GND
  DQ10_A  = M_B_CPU0_SA_DQ<10>
  VSS70  = GND
  DQ11_A  = M_B_CPU0_SA_DQ<11>
  VSS71  = GND
  \dqs6_a_c||tdqs6_a_c||dqs6_a_t||tdqs6_a_t\  = M_B_CPU0_SA_DQS_DN<6>
  \dqs6_a_t||tdqs6_a_t\  = M_B_CPU0_SA_DQS_DP<6>
  VSS72  = GND
  DQ14_A  = M_B_CPU0_SA_DQ<14>
  VSS73  = GND
  DQ15_A  = M_B_CPU0_SA_DQ<15>
  VSS74  = GND
  DQ18_A  = M_B_CPU0_SA_DQ<18>
  VSS75  = GND
  DQ19_A  = M_B_CPU0_SA_DQ<19>
  VSS76  = GND
  \dqs7_a_c||tdqs7_a_c\  = M_B_CPU0_SA_DQS_DN<7>
  \dqs7_a_t||tdqs7_a_t\  = M_B_CPU0_SA_DQS_DP<7>
  VSS77  = GND
  DQ22_A  = M_B_CPU0_SA_DQ<22>
  VSS78  = GND
  DQ23_A  = M_B_CPU0_SA_DQ<23>
  VSS79  = GND
  DQ26_A  = M_B_CPU0_SA_DQ<26>
  VSS80  = GND
  DQ27_A  = M_B_CPU0_SA_DQ<27>
  VSS81  = GND
  \dqs8_a_c||tdqs8_a_c\  = M_B_CPU0_SA_DQS_DN<8>
  \dqs8_a_t||tdqs8_a_t\  = M_B_CPU0_SA_DQS_DP<8>
  VSS82  = GND
  DQ30_A  = M_B_CPU0_SA_DQ<30>
  VSS83  = GND
  DQ31_A  = M_B_CPU0_SA_DQ<31>
  VSS84  = GND
  CB2_A  = M_B_CPU0_SA_CB<2>
  VSS85  = GND
  CB3_A  = M_B_CPU0_SA_CB<3>
  VSS86  = GND
  \dqs9_a_c||tdqs9_a_c\  = M_B_CPU0_SA_DQS_DN<9>
  \dqs9_a_t||tdqs9_a_t\  = M_B_CPU0_SA_DQS_DP<9>
  VSS87  = GND
  CB6_A  = M_B_CPU0_SA_CB<6>
  VSS88  = GND
  CB7_A  = M_B_CPU0_SA_CB<7>
  VSS89  = GND
  RESET_N  = RST_M_AB_CPU0_FPGA_N
  VSS90  = GND
  CS1_A_N  = M_B_CPU0_SA_CS_N<3>
  VSS91  = GND
  CA1_A  = M_B_CPU0_SA_CA<1>
  VSS92  = GND
  CA3_A  = M_B_CPU0_SA_CA<3>
  VSS93  = GND
  CA5_A  = M_B_CPU0_SA_CA<5>
  VSS94  = GND
  CK_T  = M_B_CPU0_CLK_DP<1>
  CK_C  = M_B_CPU0_CLK_DN<1>
  VSS95  = GND
  RFU4  = TP_CHB_CPU0_DIMM2_FRU_4
  CA1_B  = M_B_CPU0_SB_CA<1>
  VSS96  = GND
  CA3_B  = M_B_CPU0_SB_CA<3>
  VSS97  = GND
  CA5_B  = M_B_CPU0_SB_CA<5>
  VSS98  = GND
  PAR_B  = M_B_CPU0_SB_PAR
  VSS99  = GND
  CS1_B_N  = M_B_CPU0_SB_CS_N<3>
  VSS100  = GND
  RFU5  = TP_CHB_CPU0_DIMM2_FRU_5
  RFU6  = TP_CHB_CPU0_DIMM2_FRU_6
  VSS101  = GND
  CB6_B  = M_B_CPU0_SB_CB<6>
  VSS102  = GND
  CB7_B  = M_B_CPU0_SB_CB<7>
  VSS103  = GND
  DQS4_B_C  = M_B_CPU0_SB_DQS_DN<4>
  DQS4_B_T  = M_B_CPU0_SB_DQS_DP<4>
  VSS104  = GND
  CB2_B  = M_B_CPU0_SB_CB<2>
  VSS105  = GND
  CB3_B  = M_B_CPU0_SB_CB<3>
  VSS106  = GND
  DQ2_B  = M_B_CPU0_SB_DQ<2>
  VSS107  = GND
  DQ3_B  = M_B_CPU0_SB_DQ<3>
  VSS108  = GND
  \dqs5_b_c||tdqs5_b_c\  = M_B_CPU0_SB_DQS_DN<5>
  \dqs5_b_t||tdqs5_b_t\  = M_B_CPU0_SB_DQS_DP<5>
  VSS109  = GND
  DQ6_B  = M_B_CPU0_SB_DQ<6>
  VSS110  = GND
  DQ7_B  = M_B_CPU0_SB_DQ<7>
  VSS111  = GND
  DQ10_B  = M_B_CPU0_SB_DQ<10>
  VSS112  = GND
  DQ11_B  = M_B_CPU0_SB_DQ<11>
  VSS113  = GND
  \dqs6_b_c||tdqs6_b_c\  = M_B_CPU0_SB_DQS_DN<6>
  \dqs6_b_t||tdqs6_b_t\  = M_B_CPU0_SB_DQS_DP<6>
  VSS114  = GND
  DQ14_B  = M_B_CPU0_SB_DQ<14>
  VSS115  = GND
  DQ15_B  = M_B_CPU0_SB_DQ<15>
  VSS116  = GND
  DQ18_B  = M_B_CPU0_SB_DQ<18>
  VSS117  = GND
  DQ19_B  = M_B_CPU0_SB_DQ<19>
  VSS118  = GND
  \dqs7_b_c||tdqs7_b_c\  = M_B_CPU0_SB_DQS_DN<7>
  \dqs7_b_t||tdqs7_b_t\  = M_B_CPU0_SB_DQS_DP<7>
  VSS119  = GND
  DQ22_B  = M_B_CPU0_SB_DQ<22>
  VSS120  = GND
  DQ23_B  = M_B_CPU0_SB_DQ<23>
  VSS121  = GND
  DQ26_B  = M_B_CPU0_SB_DQ<26>
  VSS122  = GND
  DQ27_B  = M_B_CPU0_SB_DQ<27>
  VSS123  = GND
  \dqs8_b_c||tdqs8_b_c\  = M_B_CPU0_SB_DQS_DN<8>
  \dqs8_b_t||tdqs8_b_t\  = M_B_CPU0_SB_DQS_DP<8>
  VSS124  = GND
  DQ30_B  = M_B_CPU0_SB_DQ<30>
  VSS125  = GND
  DQ31_B  = M_B_CPU0_SB_DQ<31>
  VSS126  = GND
  G1  = GND
  G2  = GND
  G3  = GND

(kicad_pcb
	(version 20260206)
	(generator "pcbnew")
	(generator_version "10.0")
	(general
		(thickness 1.6)
		(legacy_teardrops no)
	)
	(paper "A4")
	(title_block
		(title "03242023_DA0F0TMBIJ0_F0T_Motherboard_J_brd_V01_OCP.brd")
		(comment 1 "Grand Teton / footprint 1229 of 6105 (J4), pads 46-91 of 291")
	)
	(layers
		(0 "F.Cu" signal "TOP")
		(4 "In1.Cu" signal "GND")
		(6 "In2.Cu" signal "IN1")
		(8 "In3.Cu" signal "GND1")
		(10 "In4.Cu" signal "IN2")
		(12 "In5.Cu" signal "GND2")
		(14 "In6.Cu" signal "IN3")
		(16 "In7.Cu" signal "GND3")
		(18 "In8.Cu" signal "VCC")
		(20 "In9.Cu" signal "VCC1")
		(22 "In10.Cu" signal "GND4")
		(24 "In11.Cu" signal "IN4")
		(26 "In12.Cu" signal "GND5")
		(28 "In13.Cu" signal "IN5")
		(30 "In14.Cu" signal "GND6")
		(32 "In15.Cu" signal "IN6")
		(34 "In16.Cu" signal "GND7")
		(2 "B.Cu" signal "BOTTOM")
		(9 "F.Adhes" user "F.Adhesive")
		(11 "B.Adhes" user "B.Adhesive")
		(13 "F.Paste" user "Package Geometry/Pastemask Top")
		(15 "B.Paste" user "Package Geometry/Pastemask Bottom")
		(5 "F.SilkS" user "Ref Des/Silkscreen Top")
		(7 "B.SilkS" user "Ref Des/Silkscreen Bottom")
		(1 "F.Mask" user "Board Geometry/Soldermask Top")
		(3 "B.Mask" user "Board Geometry/Soldermask Bottom")
		(17 "Dwgs.User" user "User.Drawings")
		(19 "Cmts.User" user "User.Comments")
		(21 "Eco1.User" user "User.Eco1")
		(23 "Eco2.User" user "User.Eco2")
		(25 "Edge.Cuts" user "Board Geometry/Outline")
		(27 "Margin" user)
		(31 "F.CrtYd" user "Package Geometry/Place Bound Top")
		(29 "B.CrtYd" user "Package Geometry/Place Bound Bottom")
		(35 "F.Fab" user "Ref Des/Assembly Top")
		(33 "B.Fab" user "Ref Des/Assembly Bottom")
	)
	(footprint ""
		(layer "F.Cu")
		(at 295.849548 -258.091686)
		(property "Reference" "J4"
			(at -3.683 -81.702148 0)
			(unlocked yes)
			(layer "F.SilkS")
			(effects
				(font
					(size 0.7874 0.5842)
					(thickness 0.1524)
				)
				(justify left)
			)
		)
		(property "Value" ""
			(at 0 0 0)
			(layer "F.Fab")
			(effects
				(font
					(size 1.27 1.27)
				)
			)
		)
		(duplicate_pad_numbers_are_jumpers no)
		(pad "46" smd rect
			(at -2.050034 -25.07488 270)
			(size 0.519938 1.4986)
			(layers "F.Cu" "F.Mask" "F.Paste")
			(net "GND")
		)
		(pad "47" smd rect
			(at -2.050034 -24.224996 270)
			(size 0.519938 1.4986)
			(layers "F.Cu" "F.Mask" "F.Paste")
			(net "M_B_CPU0_SA_DQ<28>")
		)
		(pad "48" smd rect
			(at -2.050034 -23.375112 270)
			(size 0.519938 1.4986)
			(layers "F.Cu" "F.Mask" "F.Paste")
			(net "GND")
		)
		(pad "49" smd rect
			(at -2.050034 -22.524974 270)
			(size 0.519938 1.4986)
			(layers "F.Cu" "F.Mask" "F.Paste")
			(net "M_B_CPU0_SA_DQ<29>")
		)
		(pad "50" smd rect
			(at -2.050034 -21.67509 270)
			(size 0.519938 1.4986)
			(layers "F.Cu" "F.Mask" "F.Paste")
			(net "GND")
		)
		(pad "51" smd rect
			(at -2.050034 -20.824952 270)
			(size 0.519938 1.4986)
			(layers "F.Cu" "F.Mask" "F.Paste")
			(net "M_B_CPU0_SA_CB<0>")
		)
		(pad "52" smd rect
			(at -2.050034 -19.975068 270)
			(size 0.519938 1.4986)
			(layers "F.Cu" "F.Mask" "F.Paste")
			(net "GND")
		)
		(pad "53" smd rect
			(at -2.050034 -19.12493 270)
			(size 0.519938 1.4986)
			(layers "F.Cu" "F.Mask" "F.Paste")
			(net "M_B_CPU0_SA_CB<1>")
		)
		(pad "54" smd rect
			(at -2.050034 -18.275046 270)
			(size 0.519938 1.4986)
			(layers "F.Cu" "F.Mask" "F.Paste")
			(net "GND")
		)
		(pad "55" smd rect
			(at -2.050034 -17.424908 270)
			(size 0.519938 1.4986)
			(layers "F.Cu" "F.Mask" "F.Paste")
			(net "M_B_CPU0_SA_DQS_DP<4>")
		)
		(pad "56" smd rect
			(at -2.050034 -16.575024 270)
			(size 0.519938 1.4986)
			(layers "F.Cu" "F.Mask" "F.Paste")
			(net "M_B_CPU0_SA_DQS_DN<4>")
		)
		(pad "57" smd rect
			(at -2.050034 -15.724886 270)
			(size 0.519938 1.4986)
			(layers "F.Cu" "F.Mask" "F.Paste")
			(net "GND")
		)
		(pad "58" smd rect
			(at -2.050034 -14.875002 270)
			(size 0.519938 1.4986)
			(layers "F.Cu" "F.Mask" "F.Paste")
			(net "M_B_CPU0_SA_CB<4>")
		)
		(pad "59" smd rect
			(at -2.050034 -14.025118 270)
			(size 0.519938 1.4986)
			(layers "F.Cu" "F.Mask" "F.Paste")
			(net "GND")
		)
		(pad "60" smd rect
			(at -2.050034 -13.17498 270)
			(size 0.519938 1.4986)
			(layers "F.Cu" "F.Mask" "F.Paste")
			(net "M_B_CPU0_SA_CB<5>")
		)
		(pad "61" smd rect
			(at -2.050034 -12.325096 270)
			(size 0.519938 1.4986)
			(layers "F.Cu" "F.Mask" "F.Paste")
			(net "GND")
		)
		(pad "62" smd rect
			(at -2.050034 -11.474958 270)
			(size 0.519938 1.4986)
			(layers "F.Cu" "F.Mask" "F.Paste")
			(net "M_B_CPU0_ALERT_N")
		)
		(pad "63" smd rect
			(at -2.050034 -10.625074 270)
			(size 0.519938 1.4986)
			(layers "F.Cu" "F.Mask" "F.Paste")
			(net "GND")
		)
		(pad "64" smd rect
			(at -2.050034 -9.774936 270)
			(size 0.519938 1.4986)
			(layers "F.Cu" "F.Mask" "F.Paste")
			(net "M_B_CPU0_SA_CS_N<2>")
		)
		(pad "65" smd rect
			(at -2.050034 -8.925052 270)
			(size 0.519938 1.4986)
			(layers "F.Cu" "F.Mask" "F.Paste")
			(net "GND")
		)
		(pad "66" smd rect
			(at -2.050034 -8.074914 270)
			(size 0.519938 1.4986)
			(layers "F.Cu" "F.Mask" "F.Paste")
			(net "M_B_CPU0_SA_CA<0>")
		)
		(pad "67" smd rect
			(at -2.050034 -7.22503 270)
			(size 0.519938 1.4986)
			(layers "F.Cu" "F.Mask" "F.Paste")
			(net "GND")
		)
		(pad "68" smd rect
			(at -2.050034 -6.374892 270)
			(size 0.519938 1.4986)
			(layers "F.Cu" "F.Mask" "F.Paste")
			(net "M_B_CPU0_SA_CA<2>")
		)
		(pad "69" smd rect
			(at -2.050034 -5.525008 270)
			(size 0.519938 1.4986)
			(layers "F.Cu" "F.Mask" "F.Paste")
			(net "GND")
		)
		(pad "70" smd rect
			(at -2.050034 -4.675124 270)
			(size 0.519938 1.4986)
			(layers "F.Cu" "F.Mask" "F.Paste")
			(net "M_B_CPU0_SA_CA<4>")
		)
		(pad "71" smd rect
			(at -2.050034 -3.824986 270)
			(size 0.519938 1.4986)
			(layers "F.Cu" "F.Mask" "F.Paste")
			(net "GND")
		)
		(pad "72" smd rect
			(at -2.050034 -2.975102 270)
			(size 0.519938 1.4986)
			(layers "F.Cu" "F.Mask" "F.Paste")
			(net "M_B_CPU0_SA_CA<6>")
		)
		(pad "73" smd rect
			(at -2.050034 -2.124964 270)
			(size 0.519938 1.4986)
			(layers "F.Cu" "F.Mask" "F.Paste")
			(net "GND")
		)
		(pad "74" smd rect
			(at -2.050034 -1.27508 270)
			(size 0.519938 1.4986)
			(layers "F.Cu" "F.Mask" "F.Paste")
			(net "M_B_CPU0_SA_PAR")
		)
		(pad "75" smd rect
			(at -2.050034 -0.424942 270)
			(size 0.519938 1.4986)
			(layers "F.Cu" "F.Mask" "F.Paste")
			(net "GND")
		)
		(pad "76" smd rect
			(at -2.050034 5.525008 270)
			(size 0.519938 1.4986)
			(layers "F.Cu" "F.Mask" "F.Paste")
			(net "M_B_CPU0_SB_CA<0>")
		)
		(pad "77" smd rect
			(at -2.050034 6.374892 270)
			(size 0.519938 1.4986)
			(layers "F.Cu" "F.Mask" "F.Paste")
			(net "GND")
		)
		(pad "78" smd rect
			(at -2.050034 7.22503 270)
			(size 0.519938 1.4986)
			(layers "F.Cu" "F.Mask" "F.Paste")
			(net "M_B_CPU0_SB_CA<2>")
		)
		(pad "79" smd rect
			(at -2.050034 8.074914 270)
			(size 0.519938 1.4986)
			(layers "F.Cu" "F.Mask" "F.Paste")
			(net "GND")
		)
		(pad "80" smd rect
			(at -2.050034 8.925052 270)
			(size 0.519938 1.4986)
			(layers "F.Cu" "F.Mask" "F.Paste")
			(net "M_B_CPU0_SB_CA<4>")
		)
		(pad "81" smd rect
			(at -2.050034 9.774936 270)
			(size 0.519938 1.4986)
			(layers "F.Cu" "F.Mask" "F.Paste")
			(net "GND")
		)
		(pad "82" smd rect
			(at -2.050034 10.625074 270)
			(size 0.519938 1.4986)
			(layers "F.Cu" "F.Mask" "F.Paste")
			(net "M_B_CPU0_SB_CA<6>")
		)
		(pad "83" smd rect
			(at -2.050034 11.474958 270)
			(size 0.519938 1.4986)
			(layers "F.Cu" "F.Mask" "F.Paste")
			(net "GND")
		)
		(pad "84" smd rect
			(at -2.050034 12.325096 270)
			(size 0.519938 1.4986)
			(layers "F.Cu" "F.Mask" "F.Paste")
			(net "M_B_CPU0_SB_CS_N<2>")
		)
		(pad "85" smd rect
			(at -2.050034 13.17498 270)
			(size 0.519938 1.4986)
			(layers "F.Cu" "F.Mask" "F.Paste")
			(net "GND")
		)
		(pad "86" smd rect
			(at -2.050034 14.025118 270)
			(size 0.519938 1.4986)
			(layers "F.Cu" "F.Mask" "F.Paste")
			(net "M_B_CPU0_SA_RSP<1>")
		)
		(pad "87" smd rect
			(at -2.050034 14.875002 270)
			(size 0.519938 1.4986)
			(layers "F.Cu" "F.Mask" "F.Paste")
			(net "M_B_CPU0_SB_RSP<1>")
		)
		(pad "88" smd rect
			(at -2.050034 15.724886 270)
			(size 0.519938 1.4986)
			(layers "F.Cu" "F.Mask" "F.Paste")
			(net "GND")
		)
		(pad "89" smd rect
			(at -2.050034 16.575024 270)
			(size 0.519938 1.4986)
			(layers "F.Cu" "F.Mask" "F.Paste")
			(net "M_B_CPU0_SB_CB<4>")
		)
		(pad "90" smd rect
			(at -2.050034 17.424908 270)
			(size 0.519938 1.4986)
			(layers "F.Cu" "F.Mask" "F.Paste")
			(net "GND")
		)
		(pad "91" smd rect
			(at -2.050034 18.275046 270)
			(size 0.519938 1.4986)
			(layers "F.Cu" "F.Mask" "F.Paste")
			(net "M_B_CPU0_SB_CB<5>")
		)
	)
)
